(kicad_pcb
	(version 20241229)
	(generator "pcbnew")
	(generator_version "9.0")
	(general
		(thickness 1.711)
		(legacy_teardrops no)
	)
	(paper "A4")
	(title_block
		(title "Antmicro Baseboard for Jetson AGX Thor")
		(date "2026-02-18")
		(rev "1.1.0")
		(company "Antmicro Ltd")
		(comment 1 "www.antmicro.com")
		(comment 9 "footprint 110 of 1170 (J1), pads 323-403 of 699")
	)
	(layers
		(0 "F.Cu" signal)
		(4 "In1.Cu" signal)
		(6 "In2.Cu" signal)
		(8 "In3.Cu" signal)
		(10 "In4.Cu" jumper)
		(12 "In5.Cu" signal)
		(14 "In6.Cu" signal)
		(16 "In7.Cu" signal)
		(18 "In8.Cu" signal)
		(2 "B.Cu" signal)
		(9 "F.Adhes" user "F.Adhesive")
		(11 "B.Adhes" user "B.Adhesive")
		(13 "F.Paste" user)
		(15 "B.Paste" user)
		(5 "F.SilkS" user "F.Silkscreen")
		(7 "B.SilkS" user "B.Silkscreen")
		(1 "F.Mask" user)
		(3 "B.Mask" user)
		(17 "Dwgs.User" user "User.Drawings")
		(19 "Cmts.User" user "User.Comments")
		(21 "Eco1.User" user "User.Eco1")
		(23 "Eco2.User" user "User.Eco2")
		(25 "Edge.Cuts" user)
		(27 "Margin" user)
		(31 "F.CrtYd" user "F.Courtyard")
		(29 "B.CrtYd" user "B.Courtyard")
		(35 "F.Fab" user)
		(33 "B.Fab" user)
	)
	(footprint "antmicro-footprints:Conn_Hermaphroditic_Molex_203456-0003_mirrored"
		(locked yes)
		(layer "F.Cu")
		(at 116.530532 78.15)
		(descr "Mirrored version of: https://www.molex.com/content/dam/molex/molex-dot-com/products/automated/en-us/salesdrawingpdf/203/203456/2034560003_sd.pdf")
		(property "Reference" "J1"
			(at -32.25 -11.2 180)
			(layer "F.SilkS")
			(effects
				(font
					(size 0.7 0.7)
					(thickness 0.15)
				)
				(justify right top)
			)
		)
		(property "Value" "Hermaphroditic_Molex_203456-0003_CUSTOM_Jetson_AGX_Thor_H8mm"
			(at 0.1 12.9 0)
			(layer "F.Fab")
			(effects
				(font
					(size 0.7 0.7)
					(thickness 0.15)
				)
				(justify right top)
			)
		)
		(property "Datasheet" "https://www.molex.com/content/dam/molex/molex-dot-com/products/automated/en-us/salesdrawingpdf/203/203456/2034560003_sd.pdf?inline"
			(at 0.1 0.2 0)
			(layer "F.Fab")
			(hide yes)
			(effects
				(font
					(size 0.7 0.7)
					(thickness 0.15)
				)
				(justify right top)
			)
		)
		(property "Description" "Mirror Mezz Hermaphroditic Connector, 5.50mm Connector Height, BGA-Attach Mounting, 7 Pair, 11 Row, 699 Circuits, 0.76µm Gold Plating, without Pegs"
			(at 0.1 0.2 0)
			(layer "F.Fab")
			(hide yes)
			(effects
				(font
					(size 0.7 0.7)
					(thickness 0.15)
				)
				(justify right top)
			)
		)
		(property "MPN" "203456-0003"
			(at 0 0 0)
			(unlocked yes)
			(layer "F.Fab")
			(hide yes)
			(effects
				(font
					(size 1 1)
					(thickness 0.15)
				)
			)
		)
		(property "Manufacturer" "Molex"
			(at 0 0 0)
			(unlocked yes)
			(layer "F.Fab")
			(hide yes)
			(effects
				(font
					(size 1 1)
					(thickness 0.15)
				)
			)
		)
		(property "Author" "Antmicro"
			(at 0 0 0)
			(unlocked yes)
			(layer "F.Fab")
			(hide yes)
			(effects
				(font
					(size 1 1)
					(thickness 0.15)
				)
			)
		)
		(property "License" "Apache-2.0"
			(at 0 0 0)
			(unlocked yes)
			(layer "F.Fab")
			(hide yes)
			(effects
				(font
					(size 1 1)
					(thickness 0.15)
				)
			)
		)
		(sheetname "/SoM_IO/")
		(sheetfile "som_io.kicad_sch")
		(solder_mask_margin 0.05)
		(attr smd)
		(pad "F6" smd circle
			(at -25.5 0 90)
			(size 0.5 0.5)
			(layers "F.Cu" "F.Mask" "F.Paste")
			(net 168 "/Expansion connector/I2S2.SDIN")
			(pinfunction "I2S2_DIN")
			(pintype "input")
		)
		(pad "F7" smd circle
			(at -24.6 0 90)
			(size 0.5 0.5)
			(layers "F.Cu" "F.Mask" "F.Paste")
			(net 1 "GND")
			(pinfunction "GND")
			(pintype "passive")
		)
		(pad "F8" smd circle
			(at -23.7 0 90)
			(size 0.5 0.5)
			(layers "F.Cu" "F.Mask" "F.Paste")
			(net 703 "unconnected-(J1I-FSI_GPIO31-PadF8)")
			(pinfunction "FSI_GPIO31")
			(pintype "bidirectional+no_connect")
		)
		(pad "F9" smd circle
			(at -22.8 0 90)
			(size 0.5 0.5)
			(layers "F.Cu" "F.Mask" "F.Paste")
			(net 689 "/SoM_IO/USBC2_PEN_1V8")
			(pinfunction "GPIO16")
			(pintype "passive")
		)
		(pad "F10" smd circle
			(at -21.9 0 90)
			(size 0.5 0.5)
			(layers "F.Cu" "F.Mask" "F.Paste")
			(net 1242 "/SoM_IO/USBC2_ID_1V8")
			(pinfunction "GPIO15")
			(pintype "passive")
		)
		(pad "F11" smd circle
			(at -21 0 90)
			(size 0.5 0.5)
			(layers "F.Cu" "F.Mask" "F.Paste")
			(net 1 "GND")
			(pinfunction "GND")
			(pintype "passive")
		)
		(pad "F12" smd circle
			(at -20.1 0 90)
			(size 0.5 0.5)
			(layers "F.Cu" "F.Mask" "F.Paste")
			(net 766 "/Recovery USB/USB0.D+")
			(pinfunction "USB0_P")
			(pintype "bidirectional")
		)
		(pad "F13" smd circle
			(at -19.2 0 90)
			(size 0.5 0.5)
			(layers "F.Cu" "F.Mask" "F.Paste")
			(net 698 "/Recovery USB/USB0.D-")
			(pinfunction "USB0_N")
			(pintype "bidirectional")
		)
		(pad "F14" smd circle
			(at -18.3 0 90)
			(size 0.5 0.5)
			(layers "F.Cu" "F.Mask" "F.Paste")
			(net 1 "GND")
			(pinfunction "GND")
			(pintype "passive")
		)
		(pad "F15" smd circle
			(at -17 0 90)
			(size 0.5 0.5)
			(layers "F.Cu" "F.Mask" "F.Paste")
			(net 1 "GND")
			(pinfunction "GND")
			(pintype "passive")
		)
		(pad "F16" smd circle
			(at -16.1 0 90)
			(size 0.5 0.5)
			(layers "F.Cu" "F.Mask" "F.Paste")
			(net 791 "unconnected-(J1C-UPHY_REFCLK0_P-PadF16)")
			(pinfunction "UPHY_REFCLK0_P")
			(pintype "output+no_connect")
		)
		(pad "F17" smd circle
			(at -15.2 0 90)
			(size 0.5 0.5)
			(layers "F.Cu" "F.Mask" "F.Paste")
			(net 614 "unconnected-(J1C-UPHY_REFCLK0_N-PadF17)")
			(pinfunction "UPHY_REFCLK0_N")
			(pintype "output+no_connect")
		)
		(pad "F18" smd circle
			(at -14.3 0 90)
			(size 0.5 0.5)
			(layers "F.Cu" "F.Mask" "F.Paste")
			(net 1 "GND")
			(pinfunction "GND")
			(pintype "passive")
		)
		(pad "F19" smd circle
			(at -13 0 90)
			(size 0.5 0.5)
			(layers "F.Cu" "F.Mask" "F.Paste")
			(net 1 "GND")
			(pinfunction "GND")
			(pintype "passive")
		)
		(pad "F20" smd circle
			(at -12.1 0 90)
			(size 0.5 0.5)
			(layers "F.Cu" "F.Mask" "F.Paste")
			(net 1272 "/SoM_IO2/DP3.AUX_C+")
			(pinfunction "DP_AUX_CH3_P")
			(pintype "bidirectional")
		)
		(pad "F21" smd circle
			(at -11.2 0 90)
			(size 0.5 0.5)
			(layers "F.Cu" "F.Mask" "F.Paste")
			(net 1273 "/SoM_IO2/DP3.AUX_C-")
			(pinfunction "DP_AUX_CH3_N")
			(pintype "bidirectional")
		)
		(pad "F22" smd circle
			(at -10.3 0 90)
			(size 0.5 0.5)
			(layers "F.Cu" "F.Mask" "F.Paste")
			(net 1 "GND")
			(pinfunction "GND")
			(pintype "passive")
		)
		(pad "F23" smd circle
			(at -9 0 90)
			(size 0.5 0.5)
			(layers "F.Cu" "F.Mask" "F.Paste")
			(net 1 "GND")
			(pinfunction "GND")
			(pintype "passive")
		)
		(pad "F24" smd circle
			(at -8.1 0 90)
			(size 0.5 0.5)
			(layers "F.Cu" "F.Mask" "F.Paste")
			(net 646 "unconnected-(J1C-UPHY_REFCLK1_P-PadF24)")
			(pinfunction "UPHY_REFCLK1_P")
			(pintype "bidirectional+no_connect")
		)
		(pad "F25" smd circle
			(at -7.2 0 90)
			(size 0.5 0.5)
			(layers "F.Cu" "F.Mask" "F.Paste")
			(net 778 "unconnected-(J1C-UPHY_REFCLK1_N-PadF25)")
			(pinfunction "UPHY_REFCLK1_N")
			(pintype "bidirectional+no_connect")
		)
		(pad "F26" smd circle
			(at -6.3 0 90)
			(size 0.5 0.5)
			(layers "F.Cu" "F.Mask" "F.Paste")
			(net 1 "GND")
			(pinfunction "GND")
			(pintype "passive")
		)
		(pad "F27" smd circle
			(at -5 0 90)
			(size 0.5 0.5)
			(layers "F.Cu" "F.Mask" "F.Paste")
			(net 1 "GND")
			(pinfunction "GND")
			(pintype "passive")
		)
		(pad "F28" smd circle
			(at -4.1 0 90)
			(size 0.5 0.5)
			(layers "F.Cu" "F.Mask" "F.Paste")
			(net 171 "/SoM_IO2/SFI_REFCLK-")
			(pinfunction "UPHY_REFCLK2_P")
			(pintype "output")
		)
		(pad "F29" smd circle
			(at -3.2 0 90)
			(size 0.5 0.5)
			(layers "F.Cu" "F.Mask" "F.Paste")
			(net 169 "/SoM_IO2/SFI_REFCLK+")
			(pinfunction "UPHY_REFCLK2_N")
			(pintype "output")
		)
		(pad "F30" smd circle
			(at -2.3 0 90)
			(size 0.5 0.5)
			(layers "F.Cu" "F.Mask" "F.Paste")
			(net 1 "GND")
			(pinfunction "GND")
			(pintype "passive")
		)
		(pad "F31" smd circle
			(at -1 0 90)
			(size 0.5 0.5)
			(layers "F.Cu" "F.Mask" "F.Paste")
			(net 1 "GND")
			(pinfunction "GND")
			(pintype "passive")
		)
		(pad "F32" smd circle
			(at -0.1 0 90)
			(size 0.5 0.5)
			(layers "F.Cu" "F.Mask" "F.Paste")
			(net 584 "/M.2/PCIe_{C5x4}.CLK+")
			(pinfunction "UPHY_REFCLK3_P")
			(pintype "bidirectional")
		)
		(pad "F33" smd circle
			(at 0.8 0 90)
			(size 0.5 0.5)
			(layers "F.Cu" "F.Mask" "F.Paste")
			(net 592 "/M.2/PCIe_{C5x4}.CLK-")
			(pinfunction "UPHY_REFCLK3_N")
			(pintype "bidirectional")
		)
		(pad "F34" smd circle
			(at 1.7 0 90)
			(size 0.5 0.5)
			(layers "F.Cu" "F.Mask" "F.Paste")
			(net 1 "GND")
			(pinfunction "GND")
			(pintype "passive")
		)
		(pad "F35" smd circle
			(at 3 0 90)
			(size 0.5 0.5)
			(layers "F.Cu" "F.Mask" "F.Paste")
			(net 1 "GND")
			(pinfunction "GND")
			(pintype "passive")
		)
		(pad "F36" smd circle
			(at 3.9 0 90)
			(size 0.5 0.5)
			(layers "F.Cu" "F.Mask" "F.Paste")
			(net 749 "unconnected-(J1I-FSI_GPIO13-PadF36)")
			(pinfunction "FSI_GPIO13")
			(pintype "passive+no_connect")
		)
		(pad "F37" smd circle
			(at 4.8 0 90)
			(size 0.5 0.5)
			(layers "F.Cu" "F.Mask" "F.Paste")
			(net 716 "unconnected-(J1I-FSI_GPIO12-PadF37)")
			(pinfunction "FSI_GPIO12")
			(pintype "passive+no_connect")
		)
		(pad "F38" smd circle
			(at 5.7 0 90)
			(size 0.5 0.5)
			(layers "F.Cu" "F.Mask" "F.Paste")
			(net 1 "GND")
			(pinfunction "GND")
			(pintype "passive")
		)
		(pad "F39" smd circle
			(at 7 0 90)
			(size 0.5 0.5)
			(layers "F.Cu" "F.Mask" "F.Paste")
			(net 1 "GND")
			(pinfunction "GND")
			(pintype "passive")
		)
		(pad "F40" smd circle
			(at 7.9 0 90)
			(size 0.5 0.5)
			(layers "F.Cu" "F.Mask" "F.Paste")
			(net 579 "unconnected-(J1G-FSI_GPIO00-PadF40)")
			(pinfunction "FSI_GPIO00")
			(pintype "passive+no_connect")
		)
		(pad "F41" smd circle
			(at 8.8 0 90)
			(size 0.5 0.5)
			(layers "F.Cu" "F.Mask" "F.Paste")
			(net 1 "GND")
			(pinfunction "GND")
			(pintype "passive")
		)
		(pad "F42" smd circle
			(at 9.7 0 90)
			(size 0.5 0.5)
			(layers "F.Cu" "F.Mask" "F.Paste")
			(net 66 "/CSI/CAM1.CSI0_CLK-")
			(pinfunction "CSI0_CLK_N")
			(pintype "input")
		)
		(pad "F43" smd circle
			(at 10.6 0 90)
			(size 0.5 0.5)
			(layers "F.Cu" "F.Mask" "F.Paste")
			(net 136 "/CSI/CAM1.CSI0_CLK+")
			(pinfunction "CSI0_CLK_P")
			(pintype "input")
		)
		(pad "F44" smd circle
			(at 11.5 0 90)
			(size 0.5 0.5)
			(layers "F.Cu" "F.Mask" "F.Paste")
			(net 1 "GND")
			(pinfunction "GND")
			(pintype "passive")
		)
		(pad "F45" smd circle
			(at 12.4 0 90)
			(size 0.5 0.5)
			(layers "F.Cu" "F.Mask" "F.Paste")
			(net 166 "unconnected-(J1F-CSI3_CLK_N-PadF45)")
			(pinfunction "CSI3_CLK_N")
			(pintype "input+no_connect")
		)
		(pad "F46" smd circle
			(at 13.3 0 90)
			(size 0.5 0.5)
			(layers "F.Cu" "F.Mask" "F.Paste")
			(net 129 "unconnected-(J1F-CSI3_CLK_P-PadF46)")
			(pinfunction "CSI3_CLK_P")
			(pintype "input+no_connect")
		)
		(pad "F47" smd circle
			(at 14.2 0 90)
			(size 0.5 0.5)
			(layers "F.Cu" "F.Mask" "F.Paste")
			(net 1 "GND")
			(pinfunction "GND")
			(pintype "passive")
		)
		(pad "F48" smd circle
			(at 15.1 0 90)
			(size 0.5 0.5)
			(layers "F.Cu" "F.Mask" "F.Paste")
			(net 160 "/CSI/CAM2.CSI4_CLK+")
			(pinfunction "CSI4_CLK_P")
			(pintype "input")
		)
		(pad "F49" smd circle
			(at 16 0 90)
			(size 0.5 0.5)
			(layers "F.Cu" "F.Mask" "F.Paste")
			(net 84 "/CSI/CAM2.CSI4_CLK-")
			(pinfunction "CSI4_CLK_N")
			(pintype "input")
		)
		(pad "F50" smd circle
			(at 16.9 0 90)
			(size 0.5 0.5)
			(layers "F.Cu" "F.Mask" "F.Paste")
			(net 1 "GND")
			(pinfunction "GND")
			(pintype "passive")
		)
		(pad "F51" smd circle
			(at 17.8 0 90)
			(size 0.5 0.5)
			(layers "F.Cu" "F.Mask" "F.Paste")
			(net 856 "/Expansion connector/I2C8.SDA")
			(pinfunction "I2C8_DAT")
			(pintype "bidirectional")
		)
		(pad "F52" smd circle
			(at 18.7 0 90)
			(size 0.5 0.5)
			(layers "F.Cu" "F.Mask" "F.Paste")
			(net 857 "/Expansion connector/I2C8.SCL")
			(pinfunction "I2C8_CLK")
			(pintype "bidirectional")
		)
		(pad "F53" smd circle
			(at 19.6 0 90)
			(size 0.5 0.5)
			(layers "F.Cu" "F.Mask" "F.Paste")
			(net 60 "/SoM_IO/I2C3_SCL_1V8")
			(pinfunction "I2C3_CLK")
			(pintype "bidirectional")
		)
		(pad "F54" smd circle
			(at 20.5 0 90)
			(size 0.5 0.5)
			(layers "F.Cu" "F.Mask" "F.Paste")
			(net 595 "unconnected-(J1C-GPIO22-PadF54)")
			(pinfunction "GPIO22")
			(pintype "passive+no_connect")
		)
		(pad "F55" smd circle
			(at 21.4 0 90)
			(size 0.5 0.5)
			(layers "F.Cu" "F.Mask" "F.Paste")
			(net 305 "/Expansion connector/SPI3.SCK")
			(pinfunction "SPI3_CLK")
			(pintype "bidirectional")
		)
		(pad "F56" smd circle
			(at 22.3 0 90)
			(size 0.5 0.5)
			(layers "F.Cu" "F.Mask" "F.Paste")
			(net 643 "/SoM_IO/SFP_LEDG_1V8")
			(pinfunction "GPIO36")
			(pintype "passive")
		)
		(pad "F57" smd circle
			(at 23.2 0 90)
			(size 0.5 0.5)
			(layers "F.Cu" "F.Mask" "F.Paste")
			(net 1 "GND")
			(pinfunction "GND")
			(pintype "passive")
		)
		(pad "F58" smd circle
			(at 24.1 0 90)
			(size 0.5 0.5)
			(layers "F.Cu" "F.Mask" "F.Paste")
			(net 690 "/Expansion connector/CAN2.DIN")
			(pinfunction "CAN2_DIN")
			(pintype "input")
		)
		(pad "F59" smd circle
			(at 25 0 90)
			(size 0.5 0.5)
			(layers "F.Cu" "F.Mask" "F.Paste")
			(net 1290 "unconnected-(J1K-GPIO42-PadF59)")
			(pinfunction "GPIO42")
			(pintype "passive+no_connect")
		)
		(pad "F60" smd circle
			(at 25.9 0 90)
			(size 0.5 0.5)
			(layers "F.Cu" "F.Mask" "F.Paste")
			(net 173 "/Expansion connector/SPI2.MOSI")
			(pinfunction "SPI2_MOSI")
			(pintype "bidirectional")
		)
		(pad "F61" smd circle
			(at 26.8 0 90)
			(size 0.5 0.5)
			(layers "F.Cu" "F.Mask" "F.Paste")
			(net 678 "Net-(J1A-VCOMP_ALERT_N)")
			(pinfunction "VCOMP_ALERT_N")
			(pintype "bidirectional")
		)
		(pad "F62" smd circle
			(at 27.7 0 90)
			(size 0.5 0.5)
			(layers "F.Cu" "F.Mask" "F.Paste")
			(net 1 "GND")
			(pinfunction "GND")
			(pintype "passive")
		)
		(pad "F63" smd circle
			(at 28.6 0 90)
			(size 0.5 0.5)
			(layers "F.Cu" "F.Mask" "F.Paste")
			(net 12 "SYS_VIN_HV")
			(pinfunction "SYS_VIN_HV")
			(pintype "passive")
		)
		(pad "F64" smd circle
			(at 29.5 0 90)
			(size 0.5 0.5)
			(layers "F.Cu" "F.Mask" "F.Paste")
			(net 12 "SYS_VIN_HV")
			(pinfunction "SYS_VIN_HV")
			(pintype "passive")
		)
		(pad "F65" smd circle
			(at 30.4 0 90)
			(size 0.5 0.5)
			(layers "F.Cu" "F.Mask" "F.Paste")
			(net 12 "SYS_VIN_HV")
			(pinfunction "SYS_VIN_HV")
			(pintype "passive")
		)
		(pad "G1" smd circle
			(at -30.2 -1.5 90)
			(size 0.5 0.5)
			(layers "F.Cu" "F.Mask" "F.Paste")
			(net 12 "SYS_VIN_HV")
			(pinfunction "SYS_VIN_HV")
			(pintype "passive")
		)
		(pad "G2" smd circle
			(at -29.3 -1.5 90)
			(size 0.5 0.5)
			(layers "F.Cu" "F.Mask" "F.Paste")
			(net 12 "SYS_VIN_HV")
			(pinfunction "SYS_VIN_HV")
			(pintype "passive")
		)
		(pad "G3" smd circle
			(at -28.4 -1.5 90)
			(size 0.5 0.5)
			(layers "F.Cu" "F.Mask" "F.Paste")
			(net 1 "GND")
			(pinfunction "GND")
			(pintype "passive")
		)
		(pad "G4" smd circle
			(at -27.5 -1.5 90)
			(size 0.5 0.5)
			(layers "F.Cu" "F.Mask" "F.Paste")
			(net 120 "/Expansion connector/I2S2.CLK")
			(pinfunction "I2S2_CLK")
			(pintype "bidirectional")
		)
		(pad "G5" smd circle
			(at -26.6 -1.5 90)
			(size 0.5 0.5)
			(layers "F.Cu" "F.Mask" "F.Paste")
			(net 739 "Net-(J1A-GPIO56)")
			(pinfunction "GPIO56")
			(pintype "passive")
		)
		(pad "G6" smd circle
			(at -25.7 -1.5 90)
			(size 0.5 0.5)
			(layers "F.Cu" "F.Mask" "F.Paste")
			(net 57 "/SFP/MOD_ABS")
			(pinfunction "GPIO49")
			(pintype "passive")
		)
		(pad "G7" smd circle
			(at -24.8 -1.5 90)
			(size 0.5 0.5)
			(layers "F.Cu" "F.Mask" "F.Paste")
			(net 356 "/Expansion connector/GPIO.USER_BTN1")
			(pinfunction "GPIO13")
			(pintype "passive")
		)
		(pad "G8" smd circle
			(at -23.9 -1.5 90)
			(size 0.5 0.5)
			(layers "F.Cu" "F.Mask" "F.Paste")
			(net 565 "/Expansion connector/PCIe_{C3x2}.~{CLKREQ}")
			(pinfunction "PEX_C3_CLKREQ_N")
			(pintype "bidirectional")
		)
		(pad "G9" smd circle
			(at -23 -1.5 90)
			(size 0.5 0.5)
			(layers "F.Cu" "F.Mask" "F.Paste")
			(net 1 "GND")
			(pinfunction "GND")
			(pintype "passive")
		)
		(pad "G10" smd circle
			(at -22.1 -1.5 90)
			(size 0.5 0.5)
			(layers "F.Cu" "F.Mask" "F.Paste")
			(net 642 "/M.2/USB3.D-")
			(pinfunction "USB3_N")
			(pintype "bidirectional")
		)
		(pad "G11" smd circle
			(at -21.2 -1.5 90)
			(size 0.5 0.5)
			(layers "F.Cu" "F.Mask" "F.Paste")
			(net 653 "/M.2/USB3.D+")
			(pinfunction "USB3_P")
			(pintype "bidirectional")
		)
		(pad "G12" smd circle
			(at -20.3 -1.5 90)
			(size 0.5 0.5)
			(layers "F.Cu" "F.Mask" "F.Paste")
			(net 1 "GND")
			(pinfunction "GND")
			(pintype "passive")
		)
		(pad "G13" smd circle
			(at -19 -1.5 90)
			(size 0.5 0.5)
			(layers "F.Cu" "F.Mask" "F.Paste")
			(net 1 "GND")
			(pinfunction "GND")
			(pintype "passive")
		)
		(pad "G14" smd circle
			(at -18.1 -1.5 90)
			(size 0.5 0.5)
			(layers "F.Cu" "F.Mask" "F.Paste")
			(net 1261 "/SoM_IO2/DP2.TX3_C-")
			(pinfunction "DP2_D3_HDMI_CK_N")
			(pintype "output")
		)
		(pad "G15" smd circle
			(at -17.2 -1.5 90)
			(size 0.5 0.5)
			(layers "F.Cu" "F.Mask" "F.Paste")
			(net 1257 "/SoM_IO2/DP2.TX3_C+")
			(pinfunction "DP2_D3_HDMI_CK_P")
			(pintype "output")
		)
		(pad "G16" smd circle
			(at -16.3 -1.5 90)
			(size 0.5 0.5)
			(layers "F.Cu" "F.Mask" "F.Paste")
			(net 1 "GND")
			(pinfunction "GND")
			(pintype "passive")
		)
		(pad "G17" smd circle
			(at -15 -1.5 90)
			(size 0.5 0.5)
			(layers "F.Cu" "F.Mask" "F.Paste")
			(net 1 "GND")
			(pinfunction "GND")
			(pintype "passive")
		)
		(pad "G18" smd circle
			(at -14.1 -1.5 90)
			(size 0.5 0.5)
			(layers "F.Cu" "F.Mask" "F.Paste")
			(net 111 "/Expansion connector/I2S3.FS")
			(pinfunction "GPIO57")
			(pintype "passive")
		)
		(pad "G19" smd circle
			(at -13.2 -1.5 90)
			(size 0.5 0.5)
			(layers "F.Cu" "F.Mask" "F.Paste")
			(net 114 "/Expansion connector/I2S3.SDIN")
			(pinfunction "GPIO58")
			(pintype "passive")
		)
		(pad "G20" smd circle
			(at -12.3 -1.5 90)
			(size 0.5 0.5)
			(layers "F.Cu" "F.Mask" "F.Paste")
			(net 1 "GND")
			(pinfunction "GND")
			(pintype "passive")
		)
		(pad "G21" smd circle
			(at -11 -1.5 90)
			(size 0.5 0.5)
			(layers "F.Cu" "F.Mask" "F.Paste")
			(net 1 "GND")
			(pinfunction "GND")
			(pintype "passive")
		)
	)
)
